FILE_TYPE = MULTI_PHYS_TABLE;

PART '74LVC2G17GW'

{========================================================================================}
:VALUE         | PART_TYPE | MATERIAL | PART_NUMBER    = STANDARD | LIFECYCLE | PART_NUMBER   | JEDEC_TYPE | DESCRIPTION                  | MANUFTR | MANUF_PN      | RD_CMPLS_LVL | CMPLS_LVL | FROM_PJ      | CLASS | DIP_SMD | DATA            | EE_CHECK_LIST | FP_ECN | PSL | CREATOR | STATUS | CREATEDAY  ;
{========================================================================================}
 '74LVC2G17GW' | 'SMLF'    | 'IC'     | 'AL2G0017005'(!) = ''       | ''        | 'AL2G0017005' |'SOT363'| 'IC(6P) 74LVC2G17GW (SC-88)' | 'PHI'   | '74LVC2G17GW' | 'EP'         | 'EP'      | 'T6S-LOUISE' | 'IC'  | ''      | '74LVC2G17.pdf' | ''            | ''     | ''  | ''      | ''     | '20121122'
 '74LVC2G17GW' | 'SMLF'    | 'EMPTY'  | 'AL2G0017005'(!) = ''       | ''        | 'AL2G0017005' |'SOT363'| 'IC(6P) 74LVC2G17GW (SC-88)' | 'PHI'   | '74LVC2G17GW' | 'EP'         | 'EP'      | 'T6S-LOUISE' | 'IC'  | ''      | '74LVC2G17.pdf' | ''            | ''     | ''  | ''      | ''     | '20121122'

END_PART

END.

